(kicad_pcb
	(version 20260206)
	(generator "pcbnew")
	(generator_version "10.0")
	(general
		(thickness 1.6)
		(legacy_teardrops no)
	)
	(paper "A4")
	(title_block
		(title "Wiwynn_Tioga_Pass_MB.brd")
		(comment 1 "Tioga Pass / footprints 3130-3136 of 4770")
	)
	(layers
		(0 "F.Cu" signal "TOP")
		(4 "In1.Cu" signal "L2GND")
		(6 "In2.Cu" signal "L3")
		(8 "In3.Cu" signal "L4GND")
		(10 "In4.Cu" signal "L5")
		(12 "In5.Cu" signal "L6GND")
		(14 "In6.Cu" signal "L7VCC")
		(16 "In7.Cu" signal "L8VCC")
		(18 "In8.Cu" signal "L9GND")
		(20 "In9.Cu" signal "L10")
		(22 "In10.Cu" signal "L11GND")
		(24 "In11.Cu" signal "L12")
		(26 "In12.Cu" signal "L13GND")
		(2 "B.Cu" signal "BOTTOM")
		(9 "F.Adhes" user "F.Adhesive")
		(11 "B.Adhes" user "B.Adhesive")
		(13 "F.Paste" user "Package Geometry/Pastemask Top")
		(15 "B.Paste" user "Package Geometry/Pastemask Bottom")
		(5 "F.SilkS" user "Ref Des/Silkscreen Top")
		(7 "B.SilkS" user "Ref Des/Silkscreen Bottom")
		(1 "F.Mask" user "Board Geometry/Soldermask Top")
		(3 "B.Mask" user "Board Geometry/Soldermask Bottom")
		(17 "Dwgs.User" user "User.Drawings")
		(19 "Cmts.User" user "User.Comments")
		(21 "Eco1.User" user "User.Eco1")
		(23 "Eco2.User" user "User.Eco2")
		(25 "Edge.Cuts" user "Board Geometry/Outline")
		(27 "Margin" user)
		(31 "F.CrtYd" user "Package Geometry/Place Bound Top")
		(29 "B.CrtYd" user "Package Geometry/Place Bound Bottom")
		(35 "F.Fab" user "Ref Des/Assembly Top")
		(33 "B.Fab" user "Ref Des/Assembly Bottom")
	)
	(footprint ""
		(layer "B.Cu")
		(at 439.301636 -144.935956 180)
		(property "Reference" "U25W13"
			(at 0 0 0)
			(layer "B.SilkS")
			(hide yes)
			(effects
				(font
					(size 1.27 1.27)
				)
				(justify mirror)
			)
		)
		(property "Value" "*"
			(at 5.08 -8.52805 180)
			(unlocked yes)
			(layer "B.Fab")
			(hide yes)
			(effects
				(font
					(size 0.889 0.889)
					(thickness 0.1524)
				)
				(justify mirror)
			)
		)
		(property "Device Type" "MAX4564EKA-GP_SCRET-GC1-MAX456A"
			(at 5.08 -10.05205 180)
			(unlocked yes)
			(layer "B.Fab")
			(hide yes)
			(effects
				(font
					(size 0.889 0.889)
					(thickness 0.1524)
				)
				(justify mirror)
			)
		)
		(duplicate_pad_numbers_are_jumpers no)
		(fp_line
			(start 1.8796 0.5588)
			(end 1.8796 -0.5588)
			(stroke
				(width 0.1524)
				(type default)
			)
			(layer "B.SilkS")
		)
		(fp_line
			(start 1.8796 -0.254)
			(end 1.6256 0)
			(stroke
				(width 0.1524)
				(type default)
			)
			(layer "B.SilkS")
		)
		(fp_line
			(start 1.8796 -0.5588)
			(end -1.8796 -0.5588)
			(stroke
				(width 0.1524)
				(type default)
			)
			(layer "B.SilkS")
		)
		(fp_line
			(start 1.7018 0.5588)
			(end 1.7018 2.1082)
			(stroke
				(width 0.508)
				(type default)
			)
			(layer "B.SilkS")
		)
		(fp_line
			(start 1.6256 0)
			(end 1.8796 0.254)
			(stroke
				(width 0.1524)
				(type default)
			)
			(layer "B.SilkS")
		)
		(fp_line
			(start -1.8796 0.5588)
			(end 1.8796 0.5588)
			(stroke
				(width 0.1524)
				(type default)
			)
			(layer "B.SilkS")
		)
		(fp_line
			(start -1.8796 -0.5588)
			(end -1.8796 0.5588)
			(stroke
				(width 0.1524)
				(type default)
			)
			(layer "B.SilkS")
		)
		(fp_poly
			(pts
				(xy 1.15316 0.5588) (xy -1.8796 0.5588) (xy -1.8796 -0.5588) (xy 1.15316 -0.5588)
			)
			(stroke
				(width 0)
				(type default)
			)
			(fill yes)
			(layer "B.SilkS")
		)
		(fp_rect
			(start 1.9558 2.3622)
			(end -1.9558 -2.3622)
			(stroke
				(width 0)
				(type default)
			)
			(fill no)
			(layer "B.CrtYd")
		)
		(fp_poly
			(pts
				(xy 1.9558 -2.3622) (xy -1.9558 -2.3622) (xy -1.9558 2.3622) (xy 1.9558 2.3622)
			)
			(stroke
				(width 0)
				(type default)
			)
			(fill no)
			(layer "B.Fab")
		)
		(pad "1" smd rect
			(at 0.97536 1.3462)
			(size 0.3556 1.016)
			(layers "B.Cu" "B.Mask" "B.Paste")
			(net "JTAG_BMC_TCK0")
		)
		(pad "2" smd rect
			(at 0.32512 1.3462)
			(size 0.3556 1.016)
			(layers "B.Cu" "B.Mask" "B.Paste")
			(net "P3V3_STBY")
		)
		(pad "3" smd rect
			(at -0.32512 1.3462)
			(size 0.3556 1.016)
			(layers "B.Cu" "B.Mask" "B.Paste")
			(net "BMC_TCK_MUX_SEL")
		)
		(pad "4" smd rect
			(at -0.97409 1.3462)
			(size 0.3556 1.016)
			(layers "B.Cu" "B.Mask" "B.Paste")
			(net "JTAG_BMC_TCK1")
		)
		(pad "5" smd rect
			(at -0.97409 -1.3462)
			(size 0.3556 1.016)
			(layers "B.Cu" "B.Mask" "B.Paste")
			(net "GND")
		)
		(pad "6" smd rect
			(at -0.32512 -1.3462)
			(size 0.3556 1.016)
			(layers "B.Cu" "B.Mask" "B.Paste")
			(net "GND")
		)
		(pad "7" smd rect
			(at 0.32512 -1.3462)
			(size 0.3556 1.016)
			(layers "B.Cu" "B.Mask" "B.Paste")
			(net "BMC_JTAG_SEL_N")
		)
		(pad "8" smd rect
			(at 0.97536 -1.3462)
			(size 0.3556 1.016)
			(layers "B.Cu" "B.Mask" "B.Paste")
			(net "JTAG_BMC_TCK_BUF")
		)
	)
	(footprint ""
		(layer "B.Cu")
		(at 104.5591 -17.7546 90)
		(property "Reference" "C8T5"
			(at -1.848866 0.752348 90)
			(unlocked yes)
			(layer "B.SilkS")
			(effects
				(font
					(size 1.27 0.9652)
					(thickness 0.1524)
				)
				(justify mirror)
			)
		)
		(property "Value" ""
			(at 0 0 90)
			(layer "B.Fab")
			(effects
				(font
					(size 1.27 1.27)
				)
				(justify mirror)
			)
		)
		(duplicate_pad_numbers_are_jumpers no)
		(fp_rect
			(start 0.500126 1.598422)
			(end -0.500126 -0.201422)
			(stroke
				(width 0)
				(type default)
			)
			(fill no)
			(layer "B.CrtYd")
		)
		(fp_line
			(start 0.500126 -0.201422)
			(end -0.500126 -0.201422)
			(stroke
				(width 0.1)
				(type default)
			)
			(layer "B.Fab")
		)
		(fp_line
			(start -0.500126 -0.201422)
			(end -0.500126 1.598422)
			(stroke
				(width 0.1)
				(type default)
			)
			(layer "B.Fab")
		)
		(fp_line
			(start 0.500126 1.598422)
			(end 0.500126 -0.201422)
			(stroke
				(width 0.1)
				(type default)
			)
			(layer "B.Fab")
		)
		(fp_line
			(start -0.500126 1.598422)
			(end 0.500126 1.598422)
			(stroke
				(width 0.1)
				(type default)
			)
			(layer "B.Fab")
		)
		(pad "1" smd rect
			(at 0 0)
			(size 0.889 0.9906)
			(layers "B.Cu" "B.Mask" "B.Paste")
			(net "PVDDQ_GHJ")
		)
		(pad "2" smd rect
			(at 0 1.397)
			(size 0.889 0.9906)
			(layers "B.Cu" "B.Mask" "B.Paste")
			(net "GND")
		)
		(zone
			(layer "B.Cu")
			(hatch none 0.5)
			(connect_pads
				(clearance 0)
			)
			(min_thickness 0.25)
			(keepout
				(tracks not_allowed)
				(vias allowed)
				(pads allowed)
				(copperpour not_allowed)
				(footprints allowed)
			)
			(placement
				(enabled no)
				(sheetname "")
			)
			(fill
				(thermal_gap 0.5)
				(thermal_bridge_width 0.5)
				(island_removal_mode 0)
			)
			(polygon
				(pts
					(xy 105.5116 -18.2499) (xy 105.0036 -18.2499) (xy 105.0036 -17.2593) (xy 105.5116 -17.2593)
				)
			)
		)
		(zone
			(layer "B.Cu")
			(hatch none 0.5)
			(connect_pads
				(clearance 0)
			)
			(min_thickness 0.25)
			(keepout
				(tracks allowed)
				(vias not_allowed)
				(pads allowed)
				(copperpour not_allowed)
				(footprints allowed)
			)
			(placement
				(enabled no)
				(sheetname "")
			)
			(fill
				(thermal_gap 0.5)
				(thermal_bridge_width 0.5)
				(island_removal_mode 0)
			)
			(polygon
				(pts
					(xy 105.5116 -18.2499) (xy 105.0036 -18.2499) (xy 105.0036 -17.2593) (xy 105.5116 -17.2593)
				)
			)
		)
	)
	(footprint ""
		(layer "B.Cu")
		(at 365.936276 -156.15158 180)
		(property "Reference" "C22W26"
			(at 0 0 0)
			(layer "B.SilkS")
			(hide yes)
			(effects
				(font
					(size 1.27 1.27)
				)
				(justify mirror)
			)
		)
		(property "Value" "*"
			(at 0.0762 -6.2357 180)
			(unlocked yes)
			(layer "B.Fab")
			(hide yes)
			(effects
				(font
					(size 1.27 1.016)
					(thickness 0.1524)
				)
				(justify mirror)
			)
		)
		(property "Device Type" "SC22U16V5MX-4-GP_SMD-BCG5-SC22A"
			(at 0.0762 -8.2677 180)
			(unlocked yes)
			(layer "B.Fab")
			(hide yes)
			(effects
				(font
					(size 1.27 1.016)
					(thickness 0.1524)
				)
				(justify mirror)
			)
		)
		(duplicate_pad_numbers_are_jumpers no)
		(fp_line
			(start -0.635 0)
			(end 0.635 0)
			(stroke
				(width 0.508)
				(type default)
			)
			(layer "B.SilkS")
		)
		(fp_rect
			(start 0.9652 1.778)
			(end -0.9652 -1.778)
			(stroke
				(width 0)
				(type default)
			)
			(fill no)
			(layer "B.CrtYd")
		)
		(fp_poly
			(pts
				(xy 0.9652 -1.778) (xy -0.9652 -1.778) (xy -0.9652 1.778) (xy 0.9652 1.778)
			)
			(stroke
				(width 0)
				(type default)
			)
			(fill no)
			(layer "B.Fab")
		)
		(pad "1" smd rect
			(at 0 -0.9652)
			(size 1.397 1.143)
			(layers "B.Cu" "B.Mask" "B.Paste")
			(net "VR_FET_SW_P12V_STBY_PVDDQ_DEF")
		)
		(pad "2" smd rect
			(at 0 0.9652)
			(size 1.397 1.143)
			(layers "B.Cu" "B.Mask" "B.Paste")
			(net "GND")
		)
	)
	(footprint ""
		(layer "B.Cu")
		(at 88.392 -140.208 90)
		(property "Reference" "C5G111"
			(at -1.14681 0.76708 180)
			(unlocked yes)
			(layer "B.SilkS")
			(effects
				(font
					(size 0.7874 0.5842)
					(thickness 0.1524)
				)
				(justify mirror)
			)
		)
		(property "Value" ""
			(at 0 0 90)
			(layer "B.Fab")
			(effects
				(font
					(size 1.27 1.27)
				)
				(justify mirror)
			)
		)
		(duplicate_pad_numbers_are_jumpers no)
		(fp_rect
			(start -0.4953 -0.2032)
			(end 0.4953 1.6002)
			(stroke
				(width 0)
				(type default)
			)
			(fill no)
			(layer "B.CrtYd")
		)
		(fp_line
			(start 0.4953 -0.2032)
			(end -0.4953 -0.2032)
			(stroke
				(width 0.1)
				(type default)
			)
			(layer "B.Fab")
		)
		(fp_line
			(start -0.4953 -0.2032)
			(end -0.4953 1.6002)
			(stroke
				(width 0.1)
				(type default)
			)
			(layer "B.Fab")
		)
		(fp_line
			(start 0.4953 1.6002)
			(end 0.4953 -0.2032)
			(stroke
				(width 0.1)
				(type default)
			)
			(layer "B.Fab")
		)
		(fp_line
			(start -0.4953 1.6002)
			(end 0.4953 1.6002)
			(stroke
				(width 0.1)
				(type default)
			)
			(layer "B.Fab")
		)
		(pad "1" smd rect
			(at 0 0 270)
			(size 0.762 0.889)
			(layers "B.Cu" "B.Mask" "B.Paste")
			(net "PVDDQ_KLM")
		)
		(pad "2" smd rect
			(at 0 1.397 270)
			(size 0.762 0.889)
			(layers "B.Cu" "B.Mask" "B.Paste")
			(net "GND")
		)
		(zone
			(layer "B.Cu")
			(hatch none 0.5)
			(connect_pads
				(clearance 0)
			)
			(min_thickness 0.25)
			(keepout
				(tracks not_allowed)
				(vias allowed)
				(pads allowed)
				(copperpour not_allowed)
				(footprints allowed)
			)
			(placement
				(enabled no)
				(sheetname "")
			)
			(fill
				(thermal_gap 0.5)
				(thermal_bridge_width 0.5)
				(island_removal_mode 0)
			)
			(polygon
				(pts
					(xy 88.8365 -139.827) (xy 89.3445 -139.827) (xy 89.3445 -140.589) (xy 88.8365 -140.589)
				)
			)
		)
	)
	(footprint ""
		(layer "B.Cu")
		(at 467.20506 -16.392144)
		(property "Reference" "Q8G1"
			(at -1.9812 -1.92405 0)
			(unlocked yes)
			(layer "B.SilkS")
			(effects
				(font
					(size 0.7874 0.5842)
					(thickness 0.1524)
				)
				(justify left mirror)
			)
		)
		(property "Value" ""
			(at 0 0 0)
			(layer "B.Fab")
			(effects
				(font
					(size 1.27 1.27)
				)
				(justify mirror)
			)
		)
		(duplicate_pad_numbers_are_jumpers no)
		(fp_line
			(start 0.245364 -1.379982)
			(end -3.15468 -1.379982)
			(stroke
				(width 0.1524)
				(type default)
			)
			(layer "B.SilkS")
		)
		(fp_line
			(start 0.245364 2.020062)
			(end -3.15468 2.020062)
			(stroke
				(width 0.1524)
				(type default)
			)
			(layer "B.SilkS")
		)
		(fp_circle
			(center 0.84455 -0.216154)
			(end 0.97155 -0.216154)
			(stroke
				(width 0.254)
				(type default)
			)
			(fill no)
			(layer "B.SilkS")
		)
		(fp_poly
			(pts
				(xy -0.890016 -0.82296) (xy -0.890016 1.46304) (xy -3.404616 1.46304) (xy -3.404616 1.13284) (xy -2.617216 1.13284)
				(xy -2.617216 0.811022) (xy -3.404616 0.811022) (xy -3.404616 0.480822) (xy -2.617216 0.480822)
				(xy -2.617216 0.159258) (xy -3.404616 0.159258) (xy -3.404616 -0.170942) (xy -2.617216 -0.170942)
				(xy -2.617216 -0.49276) (xy -3.404616 -0.49276) (xy -3.404616 -0.82296)
			)
			(stroke
				(width 0)
				(type default)
			)
			(fill yes)
			(layer "B.Paste")
		)
		(fp_poly
			(pts
				(xy 0.245364 -1.379982) (xy 0.245364 2.020062) (xy -3.15468 2.020062) (xy -3.15468 -1.379982)
			)
			(stroke
				(width 0)
				(type default)
			)
			(fill no)
			(layer "B.CrtYd")
		)
		(fp_line
			(start -3.15468 -1.379982)
			(end -3.15468 2.020062)
			(stroke
				(width 0.1)
				(type default)
			)
			(layer "B.Fab")
		)
		(fp_line
			(start -3.15468 2.020062)
			(end 0.245364 2.020062)
			(stroke
				(width 0.1)
				(type default)
			)
			(layer "B.Fab")
		)
		(fp_line
			(start 0.245364 -1.379982)
			(end -3.15468 -1.379982)
			(stroke
				(width 0.1)
				(type default)
			)
			(layer "B.Fab")
		)
		(fp_line
			(start 0.245364 2.020062)
			(end 0.245364 -1.379982)
			(stroke
				(width 0.1)
				(type default)
			)
			(layer "B.Fab")
		)
		(fp_circle
			(center 0.94996 -1.512316)
			(end 1.07696 -1.512316)
			(stroke
				(width 0.254)
				(type default)
			)
			(fill no)
			(layer "B.Fab")
		)
		(pad "1" smd custom
			(at 0 0 180)
			(size 0.24765 0.24765)
			(layers "B.Cu" "B.Mask" "B.Paste")
			(net "P3V3")
			(options
				(clearance outline)
				(anchor circle)
			)
			(primitives
				(gr_poly
					(pts
						(xy 0.4953 -0.8255) (xy 0.4953 0.8255) (xy -0.4953 0.8255) (xy -0.4953 0.4953) (xy 0.0127 0.4953)
						(xy 0.0127 0.1651) (xy -0.4953 0.1651) (xy -0.4953 -0.1651) (xy 0.0127 -0.1651) (xy 0.0127 -0.4953)
						(xy -0.4953 -0.4953) (xy -0.4953 -0.8255)
					)
					(width 0)
					(fill yes)
				)
			)
		)
		(pad "4" smd rect
			(at 0 1.30048 180)
			(size 0.9906 0.3302)
			(layers "B.Cu" "B.Mask" "B.Paste")
			(net "P3V3_SWITCH_G")
		)
		(pad "5" smd custom
			(at -2.147316 0.32004 180)
			(size 0.5715 0.5715)
			(layers "B.Cu" "B.Mask" "B.Paste")
			(net "P3V3_STBY")
			(options
				(clearance outline)
				(anchor circle)
			)
			(primitives
				(gr_poly
					(pts
						(xy -1.2573 1.143) (xy -1.2573 -1.143) (xy 1.2573 -1.143) (xy 1.2573 -0.8128) (xy 0.4699 -0.8128)
						(xy 0.4699 -0.490982) (xy 1.2573 -0.490982) (xy 1.2573 -0.160782) (xy 0.4699 -0.160782) (xy 0.4699 0.160782)
						(xy 1.2573 0.160782) (xy 1.2573 0.490982) (xy 0.4699 0.490982) (xy 0.4699 0.8128) (xy 1.2573 0.8128)
						(xy 1.2573 1.143)
					)
					(width 0)
					(fill yes)
				)
			)
		)
	)
	(footprint ""
		(layer "B.Cu")
		(at 198.623428 -61.285882 90)
		(property "Reference" "C4E25"
			(at 0 0 90)
			(layer "B.SilkS")
			(hide yes)
			(effects
				(font
					(size 1.27 1.27)
				)
				(justify mirror)
			)
		)
		(property "Value" "*"
			(at -1.1811 -2.8194 90)
			(unlocked yes)
			(layer "B.Fab")
			(hide yes)
			(effects
				(font
					(size 1.27 1.016)
					(thickness 0.1524)
				)
				(justify mirror)
			)
		)
		(property "Device Type" "SC1U10V2KX-4-GP_SMD-BCG6-SC1U1A"
			(at -1.1811 -4.3434 90)
			(unlocked yes)
			(layer "B.Fab")
			(hide yes)
			(effects
				(font
					(size 1.27 1.016)
					(thickness 0.1524)
				)
				(justify mirror)
			)
		)
		(duplicate_pad_numbers_are_jumpers no)
		(fp_rect
			(start 0.4318 0.9525)
			(end -0.4318 -0.9525)
			(stroke
				(width 0)
				(type default)
			)
			(fill no)
			(layer "B.CrtYd")
		)
		(fp_rect
			(start 0.4318 0.9525)
			(end -0.4318 -0.9525)
			(stroke
				(width 0)
				(type default)
			)
			(fill no)
			(layer "B.Fab")
		)
		(pad "1" smd custom
			(at 0 -0.4445 270)
			(size 0.1524 0.1524)
			(layers "B.Cu" "B.Mask" "B.Paste")
			(net "P5V_STBY")
			(options
				(clearance outline)
				(anchor circle)
			)
			(primitives
				(gr_poly
					(pts
						(arc
							(start 0.3048 0.2032)
							(mid 0.275042 0.275042)
							(end 0.2032 0.3048)
						)
						(arc
							(start -0.2032 0.3048)
							(mid -0.275042 0.275042)
							(end -0.3048 0.2032)
						)
						(arc
							(start -0.3048 -0.2032)
							(mid -0.275042 -0.275042)
							(end -0.2032 -0.3048)
						)
						(arc
							(start 0.2032 -0.3048)
							(mid 0.275042 -0.275042)
							(end 0.3048 -0.2032)
						)
					)
					(width 0)
					(fill yes)
				)
			)
		)
		(pad "2" smd custom
			(at 0 0.4445 270)
			(size 0.1524 0.1524)
			(layers "B.Cu" "B.Mask" "B.Paste")
			(net "GND")
			(options
				(clearance outline)
				(anchor circle)
			)
			(primitives
				(gr_poly
					(pts
						(arc
							(start 0.3048 0.2032)
							(mid 0.275042 0.275042)
							(end 0.2032 0.3048)
						)
						(arc
							(start -0.2032 0.3048)
							(mid -0.275042 0.275042)
							(end -0.3048 0.2032)
						)
						(arc
							(start -0.3048 -0.2032)
							(mid -0.275042 -0.275042)
							(end -0.2032 -0.3048)
						)
						(arc
							(start 0.2032 -0.3048)
							(mid 0.275042 -0.275042)
							(end 0.3048 -0.2032)
						)
					)
					(width 0)
					(fill yes)
				)
			)
		)
	)
	(footprint ""
		(layer "B.Cu")
		(at 372.411752 -42.615358 180)
		(property "Reference" "R2T31"
			(at 0 0 0)
			(layer "B.SilkS")
			(hide yes)
			(effects
				(font
					(size 1.27 1.27)
				)
				(justify mirror)
			)
		)
		(property "Value" ""
			(at 0 0 0)
			(layer "B.Fab")
			(effects
				(font
					(size 1.27 1.27)
				)
				(justify mirror)
			)
		)
		(duplicate_pad_numbers_are_jumpers no)
		(fp_poly
			(pts
				(xy 0.2794 -0.1016) (xy -0.2794 -0.1016) (xy -0.2794 0.9906) (xy 0.2794 0.9906)
			)
			(stroke
				(width 0)
				(type default)
			)
			(fill no)
			(layer "B.CrtYd")
		)
		(fp_line
			(start 0.2794 0.9906)
			(end -0.2794 0.9906)
			(stroke
				(width 0.1)
				(type default)
			)
			(layer "B.Fab")
		)
		(fp_line
			(start 0.2794 -0.1016)
			(end 0.2794 0.9906)
			(stroke
				(width 0.1)
				(type default)
			)
			(layer "B.Fab")
		)
		(fp_line
			(start -0.2794 0.9906)
			(end -0.2794 -0.1016)
			(stroke
				(width 0.1)
				(type default)
			)
			(layer "B.Fab")
		)
		(fp_line
			(start -0.2794 -0.1016)
			(end 0.2794 -0.1016)
			(stroke
				(width 0.1)
				(type default)
			)
			(layer "B.Fab")
		)
		(pad "1" smd rect
			(at 0 0)
			(size 0.508 0.508)
			(layers "B.Cu" "B.Mask" "B.Paste")
			(net "H_CPU_ERR1_GTL_R_N")
		)
		(pad "2" smd rect
			(at 0 0.889)
			(size 0.508 0.508)
			(layers "B.Cu" "B.Mask" "B.Paste")
			(net "H_CPU_ERR1_GTL_N")
		)
		(zone
			(layer "B.Cu")
			(hatch none 0.5)
			(connect_pads
				(clearance 0)
			)
			(min_thickness 0.25)
			(keepout
				(tracks not_allowed)
				(vias allowed)
				(pads allowed)
				(copperpour not_allowed)
				(footprints allowed)
			)
			(placement
				(enabled no)
				(sheetname "")
			)
			(fill
				(thermal_gap 0.5)
				(thermal_bridge_width 0.5)
				(island_removal_mode 0)
			)
			(polygon
				(pts
					(xy 372.157752 -43.250358) (xy 372.665752 -43.250358) (xy 372.665752 -42.869358) (xy 372.157752 -42.869358)
				)
			)
		)
		(zone
			(layer "B.Cu")
			(hatch none 0.5)
			(connect_pads
				(clearance 0)
			)
			(min_thickness 0.25)
			(keepout
				(tracks allowed)
				(vias not_allowed)
				(pads allowed)
				(copperpour not_allowed)
				(footprints allowed)
			)
			(placement
				(enabled no)
				(sheetname "")
			)
			(fill
				(thermal_gap 0.5)
				(thermal_bridge_width 0.5)
				(island_removal_mode 0)
			)
			(polygon
				(pts
					(xy 372.157752 -42.869358) (xy 372.665752 -42.869358) (xy 372.665752 -43.250358) (xy 372.157752 -43.250358)
				)
			)
		)
	)
)
